# T6G (Grand Teton) — schematic netlist excerpt (pin names and nets, part order shuffled) for the footprints in the layout excerpt that follows; sources: Cadence DE-HDL packaged netlist, KiCad conversion of 04192023_DAF0TMB3IC0_F0TG_MB_C_brd_V02_OCP.brd

R6826  Q_RES  0 5% CHIP  pkg 0402LF  page 81 : A = RST_RT_CPU0_P3_RESET_R2_N ; B = RST_RT_CPU0_P3_RESET_R_N
R3621  Q_RES  4.7K 1% EMPTY  pkg 0402LF  page 237 : A = P3V3_AUX ; B = INA230_4_A0

(kicad_pcb
	(version 20260206)
	(generator "pcbnew")
	(generator_version "10.0")
	(general
		(thickness 1.6)
		(legacy_teardrops no)
	)
	(paper "A4")
	(title_block
		(title "04192023_DAF0TMB3IC0_F0TG_MB_C_brd_V02_OCP.brd")
		(comment 1 "Grand Teton / footprints 983-984 of 8354")
	)
	(layers
		(0 "F.Cu" signal "TOP")
		(4 "In1.Cu" signal "GND")
		(6 "In2.Cu" signal "IN1")
		(8 "In3.Cu" signal "GND1")
		(10 "In4.Cu" signal "IN2")
		(12 "In5.Cu" signal "GND2")
		(14 "In6.Cu" signal "IN3")
		(16 "In7.Cu" signal "GND3")
		(18 "In8.Cu" signal "VCC")
		(20 "In9.Cu" signal "VCC1")
		(22 "In10.Cu" signal "GND4")
		(24 "In11.Cu" signal "IN4")
		(26 "In12.Cu" signal "GND5")
		(28 "In13.Cu" signal "IN5")
		(30 "In14.Cu" signal "GND6")
		(32 "In15.Cu" signal "IN6")
		(34 "In16.Cu" signal "GND7")
		(2 "B.Cu" signal "BOTTOM")
		(9 "F.Adhes" user "F.Adhesive")
		(11 "B.Adhes" user "B.Adhesive")
		(13 "F.Paste" user "Package Geometry/Pastemask Top")
		(15 "B.Paste" user "Package Geometry/Pastemask Bottom")
		(5 "F.SilkS" user "Ref Des/Silkscreen Top")
		(7 "B.SilkS" user "Ref Des/Silkscreen Bottom")
		(1 "F.Mask" user "Board Geometry/Soldermask Top")
		(3 "B.Mask" user "Board Geometry/Soldermask Bottom")
		(17 "Dwgs.User" user "User.Drawings")
		(19 "Cmts.User" user "User.Comments")
		(21 "Eco1.User" user "User.Eco1")
		(23 "Eco2.User" user "User.Eco2")
		(25 "Edge.Cuts" user "Board Geometry/Outline")
		(27 "Margin" user)
		(31 "F.CrtYd" user "Package Geometry/Place Bound Top")
		(29 "B.CrtYd" user "Package Geometry/Place Bound Bottom")
		(35 "F.Fab" user "Ref Des/Assembly Top")
		(33 "B.Fab" user "Ref Des/Assembly Bottom")
	)
	(footprint ""
		(layer "F.Cu")
		(at 150.502366 -55.188358)
		(property "Reference" "R3621"
			(at 0 0 0)
			(layer "F.SilkS")
			(hide yes)
			(effects
				(font
					(size 1.27 1.27)
				)
			)
		)
		(property "Value" ""
			(at 0 0 0)
			(layer "F.Fab")
			(effects
				(font
					(size 1.27 1.27)
				)
			)
		)
		(duplicate_pad_numbers_are_jumpers no)
		(fp_line
			(start -0.7874 -0.4064)
			(end 0.7874 -0.4064)
			(stroke
				(width 0.1524)
				(type default)
			)
			(layer "F.SilkS")
		)
		(fp_line
			(start -0.7874 0.4064)
			(end -0.7874 -0.4064)
			(stroke
				(width 0.1524)
				(type default)
			)
			(layer "F.SilkS")
		)
		(fp_line
			(start 0.7874 -0.4064)
			(end 0.7874 0.4064)
			(stroke
				(width 0.1524)
				(type default)
			)
			(layer "F.SilkS")
		)
		(fp_line
			(start 0.7874 0.4064)
			(end -0.7874 0.4064)
			(stroke
				(width 0.1524)
				(type default)
			)
			(layer "F.SilkS")
		)
		(fp_line
			(start -0.67945 -0.305054)
			(end -0.12065 -0.305054)
			(stroke
				(width 0.1)
				(type default)
			)
			(layer "F.Fab")
		)
		(fp_line
			(start -0.67945 0.3048)
			(end -0.67945 -0.305054)
			(stroke
				(width 0.1)
				(type default)
			)
			(layer "F.Fab")
		)
		(fp_line
			(start -0.12065 -0.305054)
			(end -0.12065 -0.2794)
			(stroke
				(width 0.1)
				(type default)
			)
			(layer "F.Fab")
		)
		(fp_line
			(start -0.12065 -0.2794)
			(end 0.12065 -0.2794)
			(stroke
				(width 0.1)
				(type default)
			)
			(layer "F.Fab")
		)
		(fp_line
			(start -0.12065 0.2794)
			(end -0.12065 0.3048)
			(stroke
				(width 0.1)
				(type default)
			)
			(layer "F.Fab")
		)
		(fp_line
			(start -0.12065 0.3048)
			(end -0.67945 0.3048)
			(stroke
				(width 0.1)
				(type default)
			)
			(layer "F.Fab")
		)
		(fp_line
			(start 0.120396 0.2794)
			(end -0.12065 0.2794)
			(stroke
				(width 0.1)
				(type default)
			)
			(layer "F.Fab")
		)
		(fp_line
			(start 0.120396 0.3048)
			(end 0.120396 0.2794)
			(stroke
				(width 0.1)
				(type default)
			)
			(layer "F.Fab")
		)
		(fp_line
			(start 0.12065 -0.3048)
			(end 0.67945 -0.3048)
			(stroke
				(width 0.1)
				(type default)
			)
			(layer "F.Fab")
		)
		(fp_line
			(start 0.12065 -0.2794)
			(end 0.12065 -0.3048)
			(stroke
				(width 0.1)
				(type default)
			)
			(layer "F.Fab")
		)
		(fp_line
			(start 0.67945 -0.3048)
			(end 0.67945 0.3048)
			(stroke
				(width 0.1)
				(type default)
			)
			(layer "F.Fab")
		)
		(fp_line
			(start 0.67945 0.3048)
			(end 0.120396 0.3048)
			(stroke
				(width 0.1)
				(type default)
			)
			(layer "F.Fab")
		)
		(pad "1" smd circle
			(at -0.40005 0)
			(size 0 0)
			(layers "F.Cu" "F.Mask" "F.Paste")
			(net "P3V3_AUX")
		)
		(pad "2" smd circle
			(at 0.40005 0)
			(size 0 0)
			(layers "F.Cu" "F.Mask" "F.Paste")
			(net "INA230_4_A0")
		)
	)
	(footprint ""
		(layer "F.Cu")
		(at 217.047826 -125.62459)
		(property "Reference" "R6826"
			(at 0 0 0)
			(layer "F.SilkS")
			(hide yes)
			(effects
				(font
					(size 1.27 1.27)
				)
			)
		)
		(property "Value" ""
			(at 0 0 0)
			(layer "F.Fab")
			(effects
				(font
					(size 1.27 1.27)
				)
			)
		)
		(duplicate_pad_numbers_are_jumpers no)
		(fp_line
			(start -0.7874 -0.4064)
			(end 0.7874 -0.4064)
			(stroke
				(width 0.1524)
				(type default)
			)
			(layer "F.SilkS")
		)
		(fp_line
			(start -0.7874 0.4064)
			(end -0.7874 -0.4064)
			(stroke
				(width 0.1524)
				(type default)
			)
			(layer "F.SilkS")
		)
		(fp_line
			(start 0.7874 -0.4064)
			(end 0.7874 0.4064)
			(stroke
				(width 0.1524)
				(type default)
			)
			(layer "F.SilkS")
		)
		(fp_line
			(start 0.7874 0.4064)
			(end -0.7874 0.4064)
			(stroke
				(width 0.1524)
				(type default)
			)
			(layer "F.SilkS")
		)
		(fp_line
			(start -0.67945 -0.305054)
			(end -0.12065 -0.305054)
			(stroke
				(width 0.1)
				(type default)
			)
			(layer "F.Fab")
		)
		(fp_line
			(start -0.67945 0.3048)
			(end -0.67945 -0.305054)
			(stroke
				(width 0.1)
				(type default)
			)
			(layer "F.Fab")
		)
		(fp_line
			(start -0.12065 -0.305054)
			(end -0.12065 -0.2794)
			(stroke
				(width 0.1)
				(type default)
			)
			(layer "F.Fab")
		)
		(fp_line
			(start -0.12065 -0.2794)
			(end 0.12065 -0.2794)
			(stroke
				(width 0.1)
				(type default)
			)
			(layer "F.Fab")
		)
		(fp_line
			(start -0.12065 0.2794)
			(end -0.12065 0.3048)
			(stroke
				(width 0.1)
				(type default)
			)
			(layer "F.Fab")
		)
		(fp_line
			(start -0.12065 0.3048)
			(end -0.67945 0.3048)
			(stroke
				(width 0.1)
				(type default)
			)
			(layer "F.Fab")
		)
		(fp_line
			(start 0.120396 0.2794)
			(end -0.12065 0.2794)
			(stroke
				(width 0.1)
				(type default)
			)
			(layer "F.Fab")
		)
		(fp_line
			(start 0.120396 0.3048)
			(end 0.120396 0.2794)
			(stroke
				(width 0.1)
				(type default)
			)
			(layer "F.Fab")
		)
		(fp_line
			(start 0.12065 -0.3048)
			(end 0.67945 -0.3048)
			(stroke
				(width 0.1)
				(type default)
			)
			(layer "F.Fab")
		)
		(fp_line
			(start 0.12065 -0.2794)
			(end 0.12065 -0.3048)
			(stroke
				(width 0.1)
				(type default)
			)
			(layer "F.Fab")
		)
		(fp_line
			(start 0.67945 -0.3048)
			(end 0.67945 0.3048)
			(stroke
				(width 0.1)
				(type default)
			)
			(layer "F.Fab")
		)
		(fp_line
			(start 0.67945 0.3048)
			(end 0.120396 0.3048)
			(stroke
				(width 0.1)
				(type default)
			)
			(layer "F.Fab")
		)
		(pad "1" smd circle
			(at -0.40005 0)
			(size 0 0)
			(layers "F.Cu" "F.Mask" "F.Paste")
			(net "RST_RT_CPU0_P3_RESET_R2_N")
		)
		(pad "2" smd circle
			(at 0.40005 0)
			(size 0 0)
			(layers "F.Cu" "F.Mask" "F.Paste")
			(net "RST_RT_CPU0_P3_RESET_R_N")
		)
	)
)
